FILE_TYPE = MULTI_PHYS_TABLE;
PART 'CHOKE_4PIN'
{=======================================================================================================================================================================================================}
:VALUE       | PACK_TYPE | MATERIAL | PART_NUMBER     = EnvComp | PART_NUMBER | JEDEC_TYPE | VALUE       | CLASS      | DESCRIPTION                   | HEIGHT     | COMPONENT_TYPE | LEAD_LENGTH | LPID  | SPEED_URL | Status |RPL| AML | Bus_Unit | Days ;
{=======================================================================================================================================================================================================}
'90 OHM'     | 'SMLF'    | 'IND'    | '752402-015'(!) = 'YES;YES;YES;UNK;ok;VLD' | '752402-015'| 'SMI0805B' | '90 OHM'    | 'DISCRETE' | '(VERIFY PINOUT BEFORE USING)COMMON MODE CHOKE 90 OHM'    | '0.055 IN' | 'SMALLSMT'     | ''          | '' | 'http://speed.intel.com:8081/speed/module/pdm/item/pdm_item_detail_direct.asp?item_cde=752402-015&item_rev=01&url_param=unused' | 'Approved' | 'YES' | '4' | 'SMO_BOARDS' | '70' 
'90 OHM'     | 'SMLF'    | 'EMPTY'  | '752402-015'(!) = 'YES;YES;YES;UNK;ok;VLD' | '752402-015'| 'SMI0805B' | 'NA'        | 'DISCRETE' | '(VERIFY PINOUT BEFORE USING)COMMON MODE CHOKE 90 OHM'    | '0.055 IN' | 'SMALLSMT'     | ''          | '' | 'http://speed.intel.com:8081/speed/module/pdm/item/pdm_item_detail_direct.asp?item_cde=752402-015&item_rev=01&url_param=unused' | 'Approved' | 'YES' | '4' | 'SMO_BOARDS' | '70' 
'67 OHM'     | 'SM_B'    | 'IND'    | '752402-028'(!) = 'UNK;UNK;UNK;UNK;ok;CIP' | '752402-028'| 'SMI0805C' | '67 OHM'    | 'DISCRETE' | 'USE SYM 2 - COMMON MODE CHOKE 67 OHM'    | '0.055 IN' | 'SMALLSMT'     | ''          | '270' | 'http://speed.intel.com:8081/speed/module/pdm/item/pdm_item_detail_direct.asp?item_cde=752402-028&item_rev=01&url_param=unused' | 'Design' | 'YES' | '1' | 'SMO_BOARDS' | '???' 
'67 OHM'     | 'SM_B'    | 'EMPTY'  | '752402-028'(!) = 'UNK;UNK;UNK;UNK;ok;CIP' | '752402-028'| 'SMI0805C' | 'NA'        | 'DISCRETE' | 'USE SYM 2 - COMMON MODE CHOKE 67 OHM'    | '0.055 IN' | 'SMALLSMT'     | ''          | '270' | 'http://speed.intel.com:8081/speed/module/pdm/item/pdm_item_detail_direct.asp?item_cde=752402-028&item_rev=01&url_param=unused' | 'Design' | 'YES' | '1' | 'SMO_BOARDS' | '???' 
END_PART
END.
